#ISCELL
  pure_quanta quanta_title_block_c *
  *
#CELL
  pure_quanta pt5161lrs *
  page396_i1
#ISCELL
  standard tap *
  page396_i10
#ISCELL
  standard tap *
  page396_i11
#ISCELL
  standard tap *
  page396_i12
#ISCELL
  standard tap *
  page396_i13
#ISCELL
  standard tap *
  page396_i14
#ISCELL
  standard tap *
  page396_i15
#ISCELL
  standard tap *
  page396_i16
#ISCELL
  standard tap *
  page396_i17
#ISCELL
  standard offpage *
  page396_i18
#ISCELL
  standard offpage *
  page396_i19
#ISCELL
  standard tap *
  page396_i2
#ISCELL
  standard tap *
  page396_i20
#ISCELL
  standard tap *
  page396_i21
#ISCELL
  standard tap *
  page396_i22
#ISCELL
  standard tap *
  page396_i23
#ISCELL
  standard tap *
  page396_i24
#ISCELL
  standard tap *
  page396_i25
#ISCELL
  standard tap *
  page396_i26
#ISCELL
  standard tap *
  page396_i27
#ISCELL
  standard tap *
  page396_i28
#ISCELL
  standard tap *
  page396_i29
#ISCELL
  standard tap *
  page396_i3
#ISCELL
  standard tap *
  page396_i30
#ISCELL
  standard tap *
  page396_i31
#ISCELL
  standard tap *
  page396_i32
#ISCELL
  standard tap *
  page396_i33
#ISCELL
  standard tap *
  page396_i34
#ISCELL
  standard tap *
  page396_i35
#ISCELL
  standard offpage *
  page396_i36
#ISCELL
  standard offpage *
  page396_i37
#CELL
  pure_quanta pt5161lrs *
  page396_i38
#ISCELL
  standard tap *
  page396_i4
#ISCELL
  standard tap *
  page396_i5
#ISCELL
  standard tap *
  page396_i6
#ISCELL
  standard tap *
  page396_i7
#ISCELL
  standard tap *
  page396_i8
#ISCELL
  standard tap *
  page396_i9
